# T6G (Grand Teton) — schematic netlist excerpt (pin names and nets, part order shuffled) for the footprints in the layout excerpt that follows; sources: Cadence DE-HDL packaged netlist, KiCad conversion of 04192023_DAF0TMB3IC0_F0TG_MB_C_brd_V02_OCP.brd

PC208_2  Q_CAP  0.1UF 25V 10% X7R  pkg 0402  page 208 : A = SW_P12V_AUX_PVDD11_S3_P0_FLT ; B = GND
R2899  Q_RES  0 5% CHIP  pkg 0402LF  page 248 : A = SMB_BMC_GPU_EN ; B = SMB_BMC_GPU_EN_R1

(kicad_pcb
	(version 20260206)
	(generator "pcbnew")
	(generator_version "10.0")
	(general
		(thickness 1.6)
		(legacy_teardrops no)
	)
	(paper "A4")
	(title_block
		(title "04192023_DAF0TMB3IC0_F0TG_MB_C_brd_V02_OCP.brd")
		(comment 1 "Grand Teton / footprints 178-179 of 8354")
	)
	(layers
		(0 "F.Cu" signal "TOP")
		(4 "In1.Cu" signal "GND")
		(6 "In2.Cu" signal "IN1")
		(8 "In3.Cu" signal "GND1")
		(10 "In4.Cu" signal "IN2")
		(12 "In5.Cu" signal "GND2")
		(14 "In6.Cu" signal "IN3")
		(16 "In7.Cu" signal "GND3")
		(18 "In8.Cu" signal "VCC")
		(20 "In9.Cu" signal "VCC1")
		(22 "In10.Cu" signal "GND4")
		(24 "In11.Cu" signal "IN4")
		(26 "In12.Cu" signal "GND5")
		(28 "In13.Cu" signal "IN5")
		(30 "In14.Cu" signal "GND6")
		(32 "In15.Cu" signal "IN6")
		(34 "In16.Cu" signal "GND7")
		(2 "B.Cu" signal "BOTTOM")
		(9 "F.Adhes" user "F.Adhesive")
		(11 "B.Adhes" user "B.Adhesive")
		(13 "F.Paste" user "Package Geometry/Pastemask Top")
		(15 "B.Paste" user "Package Geometry/Pastemask Bottom")
		(5 "F.SilkS" user "Ref Des/Silkscreen Top")
		(7 "B.SilkS" user "Ref Des/Silkscreen Bottom")
		(1 "F.Mask" user "Board Geometry/Soldermask Top")
		(3 "B.Mask" user "Board Geometry/Soldermask Bottom")
		(17 "Dwgs.User" user "User.Drawings")
		(19 "Cmts.User" user "User.Comments")
		(21 "Eco1.User" user "User.Eco1")
		(23 "Eco2.User" user "User.Eco2")
		(25 "Edge.Cuts" user "Board Geometry/Outline")
		(27 "Margin" user)
		(31 "F.CrtYd" user "Package Geometry/Place Bound Top")
		(29 "B.CrtYd" user "Package Geometry/Place Bound Bottom")
		(35 "F.Fab" user "Ref Des/Assembly Top")
		(33 "B.Fab" user "Ref Des/Assembly Bottom")
	)
	(footprint ""
		(layer "F.Cu")
		(at 27.686 -434.9623 180)
		(property "Reference" "R2899"
			(at 0 0 180)
			(layer "F.SilkS")
			(hide yes)
			(effects
				(font
					(size 1.27 1.27)
				)
			)
		)
		(property "Value" ""
			(at 0 0 180)
			(layer "F.Fab")
			(effects
				(font
					(size 1.27 1.27)
				)
			)
		)
		(duplicate_pad_numbers_are_jumpers no)
		(fp_line
			(start 0.7874 0.4064)
			(end -0.7874 0.4064)
			(stroke
				(width 0.1524)
				(type default)
			)
			(layer "F.SilkS")
		)
		(fp_line
			(start 0.7874 -0.4064)
			(end 0.7874 0.4064)
			(stroke
				(width 0.1524)
				(type default)
			)
			(layer "F.SilkS")
		)
		(fp_line
			(start -0.7874 0.4064)
			(end -0.7874 -0.4064)
			(stroke
				(width 0.1524)
				(type default)
			)
			(layer "F.SilkS")
		)
		(fp_line
			(start -0.7874 -0.4064)
			(end 0.7874 -0.4064)
			(stroke
				(width 0.1524)
				(type default)
			)
			(layer "F.SilkS")
		)
		(fp_line
			(start 0.67945 0.3048)
			(end 0.120396 0.3048)
			(stroke
				(width 0.1)
				(type default)
			)
			(layer "F.Fab")
		)
		(fp_line
			(start 0.67945 -0.3048)
			(end 0.67945 0.3048)
			(stroke
				(width 0.1)
				(type default)
			)
			(layer "F.Fab")
		)
		(fp_line
			(start 0.12065 -0.2794)
			(end 0.12065 -0.3048)
			(stroke
				(width 0.1)
				(type default)
			)
			(layer "F.Fab")
		)
		(fp_line
			(start 0.12065 -0.3048)
			(end 0.67945 -0.3048)
			(stroke
				(width 0.1)
				(type default)
			)
			(layer "F.Fab")
		)
		(fp_line
			(start 0.120396 0.3048)
			(end 0.120396 0.2794)
			(stroke
				(width 0.1)
				(type default)
			)
			(layer "F.Fab")
		)
		(fp_line
			(start 0.120396 0.2794)
			(end -0.12065 0.2794)
			(stroke
				(width 0.1)
				(type default)
			)
			(layer "F.Fab")
		)
		(fp_line
			(start -0.12065 0.3048)
			(end -0.67945 0.3048)
			(stroke
				(width 0.1)
				(type default)
			)
			(layer "F.Fab")
		)
		(fp_line
			(start -0.12065 0.2794)
			(end -0.12065 0.3048)
			(stroke
				(width 0.1)
				(type default)
			)
			(layer "F.Fab")
		)
		(fp_line
			(start -0.12065 -0.2794)
			(end 0.12065 -0.2794)
			(stroke
				(width 0.1)
				(type default)
			)
			(layer "F.Fab")
		)
		(fp_line
			(start -0.12065 -0.305054)
			(end -0.12065 -0.2794)
			(stroke
				(width 0.1)
				(type default)
			)
			(layer "F.Fab")
		)
		(fp_line
			(start -0.67945 0.3048)
			(end -0.67945 -0.305054)
			(stroke
				(width 0.1)
				(type default)
			)
			(layer "F.Fab")
		)
		(fp_line
			(start -0.67945 -0.305054)
			(end -0.12065 -0.305054)
			(stroke
				(width 0.1)
				(type default)
			)
			(layer "F.Fab")
		)
		(pad "1" smd circle
			(at -0.40005 0 180)
			(size 0 0)
			(layers "F.Cu" "F.Mask" "F.Paste")
			(net "SMB_BMC_GPU_EN")
		)
		(pad "2" smd circle
			(at 0.40005 0 180)
			(size 0 0)
			(layers "F.Cu" "F.Mask" "F.Paste")
			(net "SMB_BMC_GPU_EN_R1")
		)
	)
	(footprint ""
		(layer "F.Cu")
		(at 436.613046 -351.22866 -90)
		(property "Reference" "PC208_2"
			(at 0 0 270)
			(layer "F.SilkS")
			(hide yes)
			(effects
				(font
					(size 1.27 1.27)
				)
			)
		)
		(property "Value" ""
			(at 0 0 270)
			(layer "F.Fab")
			(effects
				(font
					(size 1.27 1.27)
				)
			)
		)
		(duplicate_pad_numbers_are_jumpers no)
		(fp_line
			(start -0.7874 0.4064)
			(end -0.7874 -0.4064)
			(stroke
				(width 0.1524)
				(type default)
			)
			(layer "F.SilkS")
		)
		(fp_line
			(start 0.7874 0.4064)
			(end -0.7874 0.4064)
			(stroke
				(width 0.1524)
				(type default)
			)
			(layer "F.SilkS")
		)
		(fp_line
			(start -0.7874 -0.4064)
			(end 0.7874 -0.4064)
			(stroke
				(width 0.1524)
				(type default)
			)
			(layer "F.SilkS")
		)
		(fp_line
			(start 0.7874 -0.4064)
			(end 0.7874 0.4064)
			(stroke
				(width 0.1524)
				(type default)
			)
			(layer "F.SilkS")
		)
		(fp_line
			(start -0.67945 0.3048)
			(end -0.67945 -0.305054)
			(stroke
				(width 0.1)
				(type default)
			)
			(layer "F.Fab")
		)
		(fp_line
			(start -0.12065 0.3048)
			(end -0.67945 0.3048)
			(stroke
				(width 0.1)
				(type default)
			)
			(layer "F.Fab")
		)
		(fp_line
			(start 0.120396 0.3048)
			(end 0.120396 0.2794)
			(stroke
				(width 0.1)
				(type default)
			)
			(layer "F.Fab")
		)
		(fp_line
			(start 0.67945 0.3048)
			(end 0.120396 0.3048)
			(stroke
				(width 0.1)
				(type default)
			)
			(layer "F.Fab")
		)
		(fp_line
			(start -0.12065 0.2794)
			(end -0.12065 0.3048)
			(stroke
				(width 0.1)
				(type default)
			)
			(layer "F.Fab")
		)
		(fp_line
			(start 0.120396 0.2794)
			(end -0.12065 0.2794)
			(stroke
				(width 0.1)
				(type default)
			)
			(layer "F.Fab")
		)
		(fp_line
			(start -0.12065 -0.2794)
			(end 0.12065 -0.2794)
			(stroke
				(width 0.1)
				(type default)
			)
			(layer "F.Fab")
		)
		(fp_line
			(start 0.12065 -0.2794)
			(end 0.12065 -0.3048)
			(stroke
				(width 0.1)
				(type default)
			)
			(layer "F.Fab")
		)
		(fp_line
			(start 0.12065 -0.3048)
			(end 0.67945 -0.3048)
			(stroke
				(width 0.1)
				(type default)
			)
			(layer "F.Fab")
		)
		(fp_line
			(start 0.67945 -0.3048)
			(end 0.67945 0.3048)
			(stroke
				(width 0.1)
				(type default)
			)
			(layer "F.Fab")
		)
		(fp_line
			(start -0.67945 -0.305054)
			(end -0.12065 -0.305054)
			(stroke
				(width 0.1)
				(type default)
			)
			(layer "F.Fab")
		)
		(fp_line
			(start -0.12065 -0.305054)
			(end -0.12065 -0.2794)
			(stroke
				(width 0.1)
				(type default)
			)
			(layer "F.Fab")
		)
		(pad "1" smd circle
			(at -0.40005 0 270)
			(size 0 0)
			(layers "F.Cu" "F.Mask" "F.Paste")
			(net "SW_P12V_AUX_PVDD11_S3_P0_FLT")
		)
		(pad "2" smd circle
			(at 0.40005 0 270)
			(size 0 0)
			(layers "F.Cu" "F.Mask" "F.Paste")
			(net "GND")
		)
	)
)
